G04 #@! TF.GenerationSoftware,KiCad,Pcbnew,(5.0.1)-3*
G04 #@! TF.CreationDate,2019-04-10T15:36:06+02:00*
G04 #@! TF.ProjectId,discovery,646973636F766572792E6B696361645F,rev?*
G04 #@! TF.SameCoordinates,PX4c4640PY8a48028*
G04 #@! TF.FileFunction,Copper,L1,Top,Signal*
G04 #@! TF.FilePolarity,Positive*
%FSLAX46Y46*%
G04 Gerber Fmt 4.6, Leading zero omitted, Abs format (unit mm)*
%MOMM*%
%LPD*%
G01*
G04 APERTURE LIST*
G04 #@! TA.AperFunction,WasherPad*
%ADD10C,4.000000*%
G04 #@! TD*
G04 #@! TA.AperFunction,ComponentPad*
%ADD11C,2.500000*%
G04 #@! TD*
G04 #@! TA.AperFunction,ComponentPad*
%ADD12C,5.000000*%
G04 #@! TD*
G04 #@! TA.AperFunction,ComponentPad*
%ADD13C,15.000000*%
G04 #@! TD*
G04 #@! TA.AperFunction,Conductor*
%ADD14C,0.254000*%
G04 #@! TD*
G04 APERTURE END LIST*
D10*
G04 #@! TO.P,J2,*
G04 #@! TO.N,*
X30101280Y53498440D03*
X30101280Y35698440D03*
D11*
G04 #@! TO.P,J2,1*
G04 #@! TO.N,+12V*
X25901280Y40398440D03*
G04 #@! TO.P,J2,2*
X25901280Y44598440D03*
G04 #@! TO.P,J2,3*
X25901280Y48798440D03*
G04 #@! TO.P,J2,4*
G04 #@! TO.N,GND*
X30101280Y40398440D03*
G04 #@! TO.P,J2,5*
X30101280Y44598440D03*
G04 #@! TO.P,J2,6*
X30101280Y48798440D03*
G04 #@! TD*
G04 #@! TO.P,J4,6*
G04 #@! TO.N,GND*
X5901280Y40398440D03*
G04 #@! TO.P,J4,5*
X5901280Y44598440D03*
G04 #@! TO.P,J4,4*
X5901280Y48798440D03*
G04 #@! TO.P,J4,3*
G04 #@! TO.N,+12V*
X10101280Y40398440D03*
G04 #@! TO.P,J4,2*
X10101280Y44598440D03*
G04 #@! TO.P,J4,1*
X10101280Y48798440D03*
D10*
G04 #@! TO.P,J4,*
G04 #@! TO.N,*
X5901280Y53498440D03*
X5901280Y35698440D03*
G04 #@! TD*
G04 #@! TO.P,J5,*
G04 #@! TO.N,*
X5901280Y6865840D03*
X5901280Y24665840D03*
D11*
G04 #@! TO.P,J5,1*
G04 #@! TO.N,+12V*
X10101280Y19965840D03*
G04 #@! TO.P,J5,2*
X10101280Y15765840D03*
G04 #@! TO.P,J5,3*
X10101280Y11565840D03*
G04 #@! TO.P,J5,4*
G04 #@! TO.N,GND*
X5901280Y19965840D03*
G04 #@! TO.P,J5,5*
X5901280Y15765840D03*
G04 #@! TO.P,J5,6*
X5901280Y11565840D03*
G04 #@! TD*
G04 #@! TO.P,J6,6*
G04 #@! TO.N,GND*
X30101280Y19965840D03*
G04 #@! TO.P,J6,5*
X30101280Y15765840D03*
G04 #@! TO.P,J6,4*
X30101280Y11565840D03*
G04 #@! TO.P,J6,3*
G04 #@! TO.N,+12V*
X25901280Y19965840D03*
G04 #@! TO.P,J6,2*
X25901280Y15765840D03*
G04 #@! TO.P,J6,1*
X25901280Y11565840D03*
D10*
G04 #@! TO.P,J6,*
G04 #@! TO.N,*
X30101280Y6865840D03*
X30101280Y24665840D03*
G04 #@! TD*
D11*
G04 #@! TO.P,J1,8*
G04 #@! TO.N,+12V*
X6101280Y66398440D03*
G04 #@! TO.P,J1,7*
X6101280Y70598440D03*
G04 #@! TO.P,J1,6*
X6101280Y74798440D03*
G04 #@! TO.P,J1,5*
X6101280Y78998440D03*
G04 #@! TO.P,J1,4*
G04 #@! TO.N,GND*
X10301280Y66398440D03*
G04 #@! TO.P,J1,3*
X10301280Y70598440D03*
G04 #@! TO.P,J1,2*
X10301280Y74798440D03*
G04 #@! TO.P,J1,1*
X10301280Y78998440D03*
D10*
G04 #@! TO.P,J1,*
G04 #@! TO.N,*
X5901280Y83698440D03*
X5901280Y61698440D03*
G04 #@! TD*
G04 #@! TO.P,J3,*
G04 #@! TO.N,*
X30101280Y83698440D03*
X30101280Y61698440D03*
D11*
G04 #@! TO.P,J3,1*
G04 #@! TO.N,GND*
X25701280Y66398440D03*
G04 #@! TO.P,J3,2*
X25701280Y70598440D03*
G04 #@! TO.P,J3,3*
X25701280Y74798440D03*
G04 #@! TO.P,J3,4*
X25701280Y78998440D03*
G04 #@! TO.P,J3,5*
G04 #@! TO.N,+12V*
X29901280Y66398440D03*
G04 #@! TO.P,J3,6*
X29901280Y70598440D03*
G04 #@! TO.P,J3,7*
X29901280Y74798440D03*
G04 #@! TO.P,J3,8*
X29901280Y78998440D03*
G04 #@! TD*
D12*
G04 #@! TO.P,W1,1*
G04 #@! TO.N,GND*
X140001280Y-1560D03*
G04 #@! TD*
G04 #@! TO.P,W2,1*
G04 #@! TO.N,GND*
X1280Y89998440D03*
G04 #@! TD*
G04 #@! TO.P,W3,1*
G04 #@! TO.N,GND*
X140001280Y89998440D03*
G04 #@! TD*
G04 #@! TO.P,W4,1*
G04 #@! TO.N,GND*
X1280Y-1560D03*
G04 #@! TD*
D13*
G04 #@! TO.P,W5,1*
G04 #@! TO.N,+12V*
X55001280Y77998440D03*
G04 #@! TD*
G04 #@! TO.P,W6,1*
G04 #@! TO.N,+12V*
X55001280Y55498440D03*
G04 #@! TD*
G04 #@! TO.P,W7,1*
G04 #@! TO.N,+12V*
X55001280Y32998440D03*
G04 #@! TD*
G04 #@! TO.P,W8,1*
G04 #@! TO.N,+12V*
X55001280Y10498440D03*
G04 #@! TD*
G04 #@! TO.P,W9,1*
G04 #@! TO.N,GND*
X115001280Y80748440D03*
G04 #@! TD*
G04 #@! TO.P,W10,1*
G04 #@! TO.N,GND*
X115001280Y58248440D03*
G04 #@! TD*
G04 #@! TO.P,W11,1*
G04 #@! TO.N,GND*
X115001280Y13248440D03*
G04 #@! TD*
G04 #@! TO.P,W12,1*
G04 #@! TO.N,GND*
X115001280Y35748440D03*
G04 #@! TD*
D14*
G04 #@! TO.N,+12V*
G36*
X143799280Y92500555D02*
X143799281Y-2503674D01*
X142503396Y-3799560D01*
X-2500835Y-3799560D01*
X-3796720Y-2503676D01*
X-3796720Y719895D01*
X-3625720Y719895D01*
X-3625720Y-723015D01*
X-3073542Y-2056090D01*
X-2053250Y-3076382D01*
X-720175Y-3628560D01*
X722735Y-3628560D01*
X2055810Y-3076382D01*
X3076102Y-2056090D01*
X3628280Y-723015D01*
X3628280Y719895D01*
X136374280Y719895D01*
X136374280Y-723015D01*
X136926458Y-2056090D01*
X137946750Y-3076382D01*
X139279825Y-3628560D01*
X140722735Y-3628560D01*
X142055810Y-3076382D01*
X143076102Y-2056090D01*
X143628280Y-723015D01*
X143628280Y719895D01*
X143076102Y2052970D01*
X142055810Y3073262D01*
X140722735Y3625440D01*
X139279825Y3625440D01*
X137946750Y3073262D01*
X136926458Y2052970D01*
X136374280Y719895D01*
X3628280Y719895D01*
X3076102Y2052970D01*
X2231811Y2897261D01*
X52703401Y2897261D01*
X53857205Y2543875D01*
X56145355Y2543875D01*
X57299159Y2897261D01*
X55001280Y5195139D01*
X52703401Y2897261D01*
X2231811Y2897261D01*
X2055810Y3073262D01*
X722735Y3625440D01*
X-720175Y3625440D01*
X-2053250Y3073262D01*
X-3073542Y2052970D01*
X-3625720Y719895D01*
X-3796720Y719895D01*
X-3796720Y25287839D01*
X2774280Y25287839D01*
X2774280Y24043841D01*
X3250337Y22894537D01*
X4129977Y22014897D01*
X4454380Y21880525D01*
X3886157Y21312302D01*
X3524280Y20438655D01*
X3524280Y19493025D01*
X3886157Y18619378D01*
X4554818Y17950717D01*
X4759729Y17865840D01*
X4554818Y17780963D01*
X3886157Y17112302D01*
X3524280Y16238655D01*
X3524280Y15293025D01*
X3886157Y14419378D01*
X4554818Y13750717D01*
X4759729Y13665840D01*
X4554818Y13580963D01*
X3886157Y12912302D01*
X3524280Y12038655D01*
X3524280Y11093025D01*
X3886157Y10219378D01*
X4454380Y9651155D01*
X4129977Y9516783D01*
X3250337Y8637143D01*
X2774280Y7487839D01*
X2774280Y6243841D01*
X3250337Y5094537D01*
X4129977Y4214897D01*
X5279281Y3738840D01*
X6523279Y3738840D01*
X7672583Y4214897D01*
X8552223Y5094537D01*
X9028280Y6243841D01*
X9028280Y7487839D01*
X8552223Y8637143D01*
X7672583Y9516783D01*
X7348180Y9651155D01*
X7803701Y10106676D01*
X9525999Y10106676D01*
X9700471Y9950861D01*
X10349006Y9920411D01*
X10502089Y9950861D01*
X10676561Y10106676D01*
X25325999Y10106676D01*
X25500471Y9950861D01*
X26149006Y9920411D01*
X26302089Y9950861D01*
X26476561Y10106676D01*
X25901280Y10681957D01*
X25325999Y10106676D01*
X10676561Y10106676D01*
X10101280Y10681957D01*
X9525999Y10106676D01*
X7803701Y10106676D01*
X7916403Y10219378D01*
X8278280Y11093025D01*
X8278280Y11318114D01*
X8455851Y11318114D01*
X8486301Y11165031D01*
X8642116Y10990559D01*
X9217397Y11565840D01*
X10985163Y11565840D01*
X11560444Y10990559D01*
X11716259Y11165031D01*
X11723446Y11318114D01*
X24255851Y11318114D01*
X24286301Y11165031D01*
X24442116Y10990559D01*
X25017397Y11565840D01*
X26785163Y11565840D01*
X27360444Y10990559D01*
X27516259Y11165031D01*
X27546709Y11813566D01*
X27516259Y11966649D01*
X27360444Y12141121D01*
X26785163Y11565840D01*
X25017397Y11565840D01*
X24442116Y12141121D01*
X24286301Y11966649D01*
X24255851Y11318114D01*
X11723446Y11318114D01*
X11746709Y11813566D01*
X11716259Y11966649D01*
X11560444Y12141121D01*
X10985163Y11565840D01*
X9217397Y11565840D01*
X8642116Y12141121D01*
X8486301Y11966649D01*
X8455851Y11318114D01*
X8278280Y11318114D01*
X8278280Y12038655D01*
X7916403Y12912302D01*
X7803701Y13025004D01*
X9525999Y13025004D01*
X10101280Y12449723D01*
X10676561Y13025004D01*
X25325999Y13025004D01*
X25901280Y12449723D01*
X26476561Y13025004D01*
X26302089Y13180819D01*
X25653554Y13211269D01*
X25500471Y13180819D01*
X25325999Y13025004D01*
X10676561Y13025004D01*
X10502089Y13180819D01*
X9853554Y13211269D01*
X9700471Y13180819D01*
X9525999Y13025004D01*
X7803701Y13025004D01*
X7247742Y13580963D01*
X7042831Y13665840D01*
X7247742Y13750717D01*
X7803701Y14306676D01*
X9525999Y14306676D01*
X9700471Y14150861D01*
X10349006Y14120411D01*
X10502089Y14150861D01*
X10676561Y14306676D01*
X25325999Y14306676D01*
X25500471Y14150861D01*
X26149006Y14120411D01*
X26302089Y14150861D01*
X26476561Y14306676D01*
X25901280Y14881957D01*
X25325999Y14306676D01*
X10676561Y14306676D01*
X10101280Y14881957D01*
X9525999Y14306676D01*
X7803701Y14306676D01*
X7916403Y14419378D01*
X8278280Y15293025D01*
X8278280Y15518114D01*
X8455851Y15518114D01*
X8486301Y15365031D01*
X8642116Y15190559D01*
X9217397Y15765840D01*
X10985163Y15765840D01*
X11560444Y15190559D01*
X11716259Y15365031D01*
X11723446Y15518114D01*
X24255851Y15518114D01*
X24286301Y15365031D01*
X24442116Y15190559D01*
X25017397Y15765840D01*
X26785163Y15765840D01*
X27360444Y15190559D01*
X27516259Y15365031D01*
X27546709Y16013566D01*
X27516259Y16166649D01*
X27360444Y16341121D01*
X26785163Y15765840D01*
X25017397Y15765840D01*
X24442116Y16341121D01*
X24286301Y16166649D01*
X24255851Y15518114D01*
X11723446Y15518114D01*
X11746709Y16013566D01*
X11716259Y16166649D01*
X11560444Y16341121D01*
X10985163Y15765840D01*
X9217397Y15765840D01*
X8642116Y16341121D01*
X8486301Y16166649D01*
X8455851Y15518114D01*
X8278280Y15518114D01*
X8278280Y16238655D01*
X7916403Y17112302D01*
X7803701Y17225004D01*
X9525999Y17225004D01*
X10101280Y16649723D01*
X10676561Y17225004D01*
X25325999Y17225004D01*
X25901280Y16649723D01*
X26476561Y17225004D01*
X26302089Y17380819D01*
X25653554Y17411269D01*
X25500471Y17380819D01*
X25325999Y17225004D01*
X10676561Y17225004D01*
X10502089Y17380819D01*
X9853554Y17411269D01*
X9700471Y17380819D01*
X9525999Y17225004D01*
X7803701Y17225004D01*
X7247742Y17780963D01*
X7042831Y17865840D01*
X7247742Y17950717D01*
X7803701Y18506676D01*
X9525999Y18506676D01*
X9700471Y18350861D01*
X10349006Y18320411D01*
X10502089Y18350861D01*
X10676561Y18506676D01*
X25325999Y18506676D01*
X25500471Y18350861D01*
X26149006Y18320411D01*
X26302089Y18350861D01*
X26476561Y18506676D01*
X25901280Y19081957D01*
X25325999Y18506676D01*
X10676561Y18506676D01*
X10101280Y19081957D01*
X9525999Y18506676D01*
X7803701Y18506676D01*
X7916403Y18619378D01*
X8278280Y19493025D01*
X8278280Y19718114D01*
X8455851Y19718114D01*
X8486301Y19565031D01*
X8642116Y19390559D01*
X9217397Y19965840D01*
X10985163Y19965840D01*
X11560444Y19390559D01*
X11716259Y19565031D01*
X11723446Y19718114D01*
X24255851Y19718114D01*
X24286301Y19565031D01*
X24442116Y19390559D01*
X25017397Y19965840D01*
X26785163Y19965840D01*
X27360444Y19390559D01*
X27516259Y19565031D01*
X27546709Y20213566D01*
X27516259Y20366649D01*
X27360444Y20541121D01*
X26785163Y19965840D01*
X25017397Y19965840D01*
X24442116Y20541121D01*
X24286301Y20366649D01*
X24255851Y19718114D01*
X11723446Y19718114D01*
X11746709Y20213566D01*
X11716259Y20366649D01*
X11560444Y20541121D01*
X10985163Y19965840D01*
X9217397Y19965840D01*
X8642116Y20541121D01*
X8486301Y20366649D01*
X8455851Y19718114D01*
X8278280Y19718114D01*
X8278280Y20438655D01*
X7916403Y21312302D01*
X7803701Y21425004D01*
X9525999Y21425004D01*
X10101280Y20849723D01*
X10676561Y21425004D01*
X25325999Y21425004D01*
X25901280Y20849723D01*
X26476561Y21425004D01*
X26302089Y21580819D01*
X25653554Y21611269D01*
X25500471Y21580819D01*
X25325999Y21425004D01*
X10676561Y21425004D01*
X10502089Y21580819D01*
X9853554Y21611269D01*
X9700471Y21580819D01*
X9525999Y21425004D01*
X7803701Y21425004D01*
X7348180Y21880525D01*
X7672583Y22014897D01*
X8552223Y22894537D01*
X9028280Y24043841D01*
X9028280Y25287839D01*
X26974280Y25287839D01*
X26974280Y24043841D01*
X27450337Y22894537D01*
X28329977Y22014897D01*
X28654380Y21880525D01*
X28086157Y21312302D01*
X27724280Y20438655D01*
X27724280Y19493025D01*
X28086157Y18619378D01*
X28754818Y17950717D01*
X28959729Y17865840D01*
X28754818Y17780963D01*
X28086157Y17112302D01*
X27724280Y16238655D01*
X27724280Y15293025D01*
X28086157Y14419378D01*
X28754818Y13750717D01*
X28959729Y13665840D01*
X28754818Y13580963D01*
X28086157Y12912302D01*
X27724280Y12038655D01*
X27724280Y11093025D01*
X28086157Y10219378D01*
X28654380Y9651155D01*
X28329977Y9516783D01*
X27450337Y8637143D01*
X26974280Y7487839D01*
X26974280Y6243841D01*
X27450337Y5094537D01*
X28329977Y4214897D01*
X29479281Y3738840D01*
X30723279Y3738840D01*
X31872583Y4214897D01*
X32752223Y5094537D01*
X33228280Y6243841D01*
X33228280Y7487839D01*
X32752223Y8637143D01*
X31872583Y9516783D01*
X31548180Y9651155D01*
X32116403Y10219378D01*
X32478280Y11093025D01*
X32478280Y11642515D01*
X47046715Y11642515D01*
X47046715Y9354365D01*
X47400101Y8200561D01*
X49697979Y10498440D01*
X60304581Y10498440D01*
X62602459Y8200561D01*
X62955845Y9354365D01*
X62955845Y11642515D01*
X62602459Y12796319D01*
X60304581Y10498440D01*
X49697979Y10498440D01*
X47400101Y12796319D01*
X47046715Y11642515D01*
X32478280Y11642515D01*
X32478280Y12038655D01*
X32116403Y12912302D01*
X31447742Y13580963D01*
X31242831Y13665840D01*
X31447742Y13750717D01*
X32116403Y14419378D01*
X32478280Y15293025D01*
X32478280Y16238655D01*
X32116403Y17112302D01*
X31447742Y17780963D01*
X31242831Y17865840D01*
X31447742Y17950717D01*
X31596644Y18099619D01*
X52703401Y18099619D01*
X55001280Y15801741D01*
X57299159Y18099619D01*
X56145355Y18453005D01*
X53857205Y18453005D01*
X52703401Y18099619D01*
X31596644Y18099619D01*
X32116403Y18619378D01*
X32478280Y19493025D01*
X32478280Y20438655D01*
X32116403Y21312302D01*
X31548180Y21880525D01*
X31872583Y22014897D01*
X32752223Y22894537D01*
X33228280Y24043841D01*
X33228280Y25287839D01*
X33182956Y25397261D01*
X52703401Y25397261D01*
X53857205Y25043875D01*
X56145355Y25043875D01*
X57299159Y25397261D01*
X55001280Y27695139D01*
X52703401Y25397261D01*
X33182956Y25397261D01*
X32752223Y26437143D01*
X31872583Y27316783D01*
X30723279Y27792840D01*
X29479281Y27792840D01*
X28329977Y27316783D01*
X27450337Y26437143D01*
X26974280Y25287839D01*
X9028280Y25287839D01*
X8552223Y26437143D01*
X7672583Y27316783D01*
X6523279Y27792840D01*
X5279281Y27792840D01*
X4129977Y27316783D01*
X3250337Y26437143D01*
X2774280Y25287839D01*
X-3796720Y25287839D01*
X-3796720Y54120439D01*
X2774280Y54120439D01*
X2774280Y52876441D01*
X3250337Y51727137D01*
X4129977Y50847497D01*
X4454380Y50713125D01*
X3886157Y50144902D01*
X3524280Y49271255D01*
X3524280Y48325625D01*
X3886157Y47451978D01*
X4554818Y46783317D01*
X4759729Y46698440D01*
X4554818Y46613563D01*
X3886157Y45944902D01*
X3524280Y45071255D01*
X3524280Y44125625D01*
X3886157Y43251978D01*
X4554818Y42583317D01*
X4759729Y42498440D01*
X4554818Y42413563D01*
X3886157Y41744902D01*
X3524280Y40871255D01*
X3524280Y39925625D01*
X3886157Y39051978D01*
X4454380Y38483755D01*
X4129977Y38349383D01*
X3250337Y37469743D01*
X2774280Y36320439D01*
X2774280Y35076441D01*
X3250337Y33927137D01*
X4129977Y33047497D01*
X5279281Y32571440D01*
X6523279Y32571440D01*
X7672583Y33047497D01*
X8552223Y33927137D01*
X9028280Y35076441D01*
X9028280Y36320439D01*
X8552223Y37469743D01*
X7672583Y38349383D01*
X7348180Y38483755D01*
X7803701Y38939276D01*
X9525999Y38939276D01*
X9700471Y38783461D01*
X10349006Y38753011D01*
X10502089Y38783461D01*
X10676561Y38939276D01*
X25325999Y38939276D01*
X25500471Y38783461D01*
X26149006Y38753011D01*
X26302089Y38783461D01*
X26476561Y38939276D01*
X25901280Y39514557D01*
X25325999Y38939276D01*
X10676561Y38939276D01*
X10101280Y39514557D01*
X9525999Y38939276D01*
X7803701Y38939276D01*
X7916403Y39051978D01*
X8278280Y39925625D01*
X8278280Y40150714D01*
X8455851Y40150714D01*
X8486301Y39997631D01*
X8642116Y39823159D01*
X9217397Y40398440D01*
X10985163Y40398440D01*
X11560444Y39823159D01*
X11716259Y39997631D01*
X11723446Y40150714D01*
X24255851Y40150714D01*
X24286301Y39997631D01*
X24442116Y39823159D01*
X25017397Y40398440D01*
X26785163Y40398440D01*
X27360444Y39823159D01*
X27516259Y39997631D01*
X27546709Y40646166D01*
X27516259Y40799249D01*
X27360444Y40973721D01*
X26785163Y40398440D01*
X25017397Y40398440D01*
X24442116Y40973721D01*
X24286301Y40799249D01*
X24255851Y40150714D01*
X11723446Y40150714D01*
X11746709Y40646166D01*
X11716259Y40799249D01*
X11560444Y40973721D01*
X10985163Y40398440D01*
X9217397Y40398440D01*
X8642116Y40973721D01*
X8486301Y40799249D01*
X8455851Y40150714D01*
X8278280Y40150714D01*
X8278280Y40871255D01*
X7916403Y41744902D01*
X7803701Y41857604D01*
X9525999Y41857604D01*
X10101280Y41282323D01*
X10676561Y41857604D01*
X25325999Y41857604D01*
X25901280Y41282323D01*
X26476561Y41857604D01*
X26302089Y42013419D01*
X25653554Y42043869D01*
X25500471Y42013419D01*
X25325999Y41857604D01*
X10676561Y41857604D01*
X10502089Y42013419D01*
X9853554Y42043869D01*
X9700471Y42013419D01*
X9525999Y41857604D01*
X7803701Y41857604D01*
X7247742Y42413563D01*
X7042831Y42498440D01*
X7247742Y42583317D01*
X7803701Y43139276D01*
X9525999Y43139276D01*
X9700471Y42983461D01*
X10349006Y42953011D01*
X10502089Y42983461D01*
X10676561Y43139276D01*
X25325999Y43139276D01*
X25500471Y42983461D01*
X26149006Y42953011D01*
X26302089Y42983461D01*
X26476561Y43139276D01*
X25901280Y43714557D01*
X25325999Y43139276D01*
X10676561Y43139276D01*
X10101280Y43714557D01*
X9525999Y43139276D01*
X7803701Y43139276D01*
X7916403Y43251978D01*
X8278280Y44125625D01*
X8278280Y44350714D01*
X8455851Y44350714D01*
X8486301Y44197631D01*
X8642116Y44023159D01*
X9217397Y44598440D01*
X10985163Y44598440D01*
X11560444Y44023159D01*
X11716259Y44197631D01*
X11723446Y44350714D01*
X24255851Y44350714D01*
X24286301Y44197631D01*
X24442116Y44023159D01*
X25017397Y44598440D01*
X26785163Y44598440D01*
X27360444Y44023159D01*
X27516259Y44197631D01*
X27546709Y44846166D01*
X27516259Y44999249D01*
X27360444Y45173721D01*
X26785163Y44598440D01*
X25017397Y44598440D01*
X24442116Y45173721D01*
X24286301Y44999249D01*
X24255851Y44350714D01*
X11723446Y44350714D01*
X11746709Y44846166D01*
X11716259Y44999249D01*
X11560444Y45173721D01*
X10985163Y44598440D01*
X9217397Y44598440D01*
X8642116Y45173721D01*
X8486301Y44999249D01*
X8455851Y44350714D01*
X8278280Y44350714D01*
X8278280Y45071255D01*
X7916403Y45944902D01*
X7803701Y46057604D01*
X9525999Y46057604D01*
X10101280Y45482323D01*
X10676561Y46057604D01*
X25325999Y46057604D01*
X25901280Y45482323D01*
X26476561Y46057604D01*
X26302089Y46213419D01*
X25653554Y46243869D01*
X25500471Y46213419D01*
X25325999Y46057604D01*
X10676561Y46057604D01*
X10502089Y46213419D01*
X9853554Y46243869D01*
X9700471Y46213419D01*
X9525999Y46057604D01*
X7803701Y46057604D01*
X7247742Y46613563D01*
X7042831Y46698440D01*
X7247742Y46783317D01*
X7803701Y47339276D01*
X9525999Y47339276D01*
X9700471Y47183461D01*
X10349006Y47153011D01*
X10502089Y47183461D01*
X10676561Y47339276D01*
X25325999Y47339276D01*
X25500471Y47183461D01*
X26149006Y47153011D01*
X26302089Y47183461D01*
X26476561Y47339276D01*
X25901280Y47914557D01*
X25325999Y47339276D01*
X10676561Y47339276D01*
X10101280Y47914557D01*
X9525999Y47339276D01*
X7803701Y47339276D01*
X7916403Y47451978D01*
X8278280Y48325625D01*
X8278280Y48550714D01*
X8455851Y48550714D01*
X8486301Y48397631D01*
X8642116Y48223159D01*
X9217397Y48798440D01*
X10985163Y48798440D01*
X11560444Y48223159D01*
X11716259Y48397631D01*
X11723446Y48550714D01*
X24255851Y48550714D01*
X24286301Y48397631D01*
X24442116Y48223159D01*
X25017397Y48798440D01*
X26785163Y48798440D01*
X27360444Y48223159D01*
X27516259Y48397631D01*
X27546709Y49046166D01*
X27516259Y49199249D01*
X27360444Y49373721D01*
X26785163Y48798440D01*
X25017397Y48798440D01*
X24442116Y49373721D01*
X24286301Y49199249D01*
X24255851Y48550714D01*
X11723446Y48550714D01*
X11746709Y49046166D01*
X11716259Y49199249D01*
X11560444Y49373721D01*
X10985163Y48798440D01*
X9217397Y48798440D01*
X8642116Y49373721D01*
X8486301Y49199249D01*
X8455851Y48550714D01*
X8278280Y48550714D01*
X8278280Y49271255D01*
X7916403Y50144902D01*
X7803701Y50257604D01*
X9525999Y50257604D01*
X10101280Y49682323D01*
X10676561Y50257604D01*
X25325999Y50257604D01*
X25901280Y49682323D01*
X26476561Y50257604D01*
X26302089Y50413419D01*
X25653554Y50443869D01*
X25500471Y50413419D01*
X25325999Y50257604D01*
X10676561Y50257604D01*
X10502089Y50413419D01*
X9853554Y50443869D01*
X9700471Y50413419D01*
X9525999Y50257604D01*
X7803701Y50257604D01*
X7348180Y50713125D01*
X7672583Y50847497D01*
X8552223Y51727137D01*
X9028280Y52876441D01*
X9028280Y54120439D01*
X26974280Y54120439D01*
X26974280Y52876441D01*
X27450337Y51727137D01*
X28329977Y50847497D01*
X28654380Y50713125D01*
X28086157Y50144902D01*
X27724280Y49271255D01*
X27724280Y48325625D01*
X28086157Y47451978D01*
X28754818Y46783317D01*
X28959729Y46698440D01*
X28754818Y46613563D01*
X28086157Y45944902D01*
X27724280Y45071255D01*
X27724280Y44125625D01*
X28086157Y43251978D01*
X28754818Y42583317D01*
X28959729Y42498440D01*
X28754818Y42413563D01*
X28086157Y41744902D01*
X27724280Y40871255D01*
X27724280Y39925625D01*
X28086157Y39051978D01*
X28654380Y38483755D01*
X28329977Y38349383D01*
X27450337Y37469743D01*
X26974280Y36320439D01*
X26974280Y35076441D01*
X27450337Y33927137D01*
X28329977Y33047497D01*
X29479281Y32571440D01*
X30723279Y32571440D01*
X31872583Y33047497D01*
X32752223Y33927137D01*
X32841435Y34142515D01*
X47046715Y34142515D01*
X47046715Y31854365D01*
X47400101Y30700561D01*
X49697979Y32998440D01*
X60304581Y32998440D01*
X62602459Y30700561D01*
X62955845Y31854365D01*
X62955845Y34142515D01*
X62602459Y35296319D01*
X60304581Y32998440D01*
X49697979Y32998440D01*
X47400101Y35296319D01*
X47046715Y34142515D01*
X32841435Y34142515D01*
X33228280Y35076441D01*
X33228280Y36320439D01*
X32752223Y37469743D01*
X31872583Y38349383D01*
X31548180Y38483755D01*
X32116403Y39051978D01*
X32478280Y39925625D01*
X32478280Y40599619D01*
X52703401Y40599619D01*
X55001280Y38301741D01*
X57299159Y40599619D01*
X56145355Y40953005D01*
X53857205Y40953005D01*
X52703401Y40599619D01*
X32478280Y40599619D01*
X32478280Y40871255D01*
X32116403Y41744902D01*
X31447742Y42413563D01*
X31242831Y42498440D01*
X31447742Y42583317D01*
X32116403Y43251978D01*
X32478280Y44125625D01*
X32478280Y45071255D01*
X32116403Y45944902D01*
X31447742Y46613563D01*
X31242831Y46698440D01*
X31447742Y46783317D01*
X32116403Y47451978D01*
X32300845Y47897261D01*
X52703401Y47897261D01*
X53857205Y47543875D01*
X56145355Y47543875D01*
X57299159Y47897261D01*
X55001280Y50195139D01*
X52703401Y47897261D01*
X32300845Y47897261D01*
X32478280Y48325625D01*
X32478280Y49271255D01*
X32116403Y50144902D01*
X31548180Y50713125D01*
X31872583Y50847497D01*
X32752223Y51727137D01*
X33228280Y52876441D01*
X33228280Y54120439D01*
X32752223Y55269743D01*
X31872583Y56149383D01*
X30723279Y56625440D01*
X29479281Y56625440D01*
X28329977Y56149383D01*
X27450337Y55269743D01*
X26974280Y54120439D01*
X9028280Y54120439D01*
X8552223Y55269743D01*
X7672583Y56149383D01*
X6523279Y56625440D01*
X5279281Y56625440D01*
X4129977Y56149383D01*
X3250337Y55269743D01*
X2774280Y54120439D01*
X-3796720Y54120439D01*
X-3796720Y56642515D01*
X47046715Y56642515D01*
X47046715Y54354365D01*
X47400101Y53200561D01*
X49697979Y55498440D01*
X60304581Y55498440D01*
X62602459Y53200561D01*
X62955845Y54354365D01*
X62955845Y56642515D01*
X62602459Y57796319D01*
X60304581Y55498440D01*
X49697979Y55498440D01*
X47400101Y57796319D01*
X47046715Y56642515D01*
X-3796720Y56642515D01*
X-3796720Y62320439D01*
X2774280Y62320439D01*
X2774280Y61076441D01*
X3250337Y59927137D01*
X4129977Y59047497D01*
X5279281Y58571440D01*
X6523279Y58571440D01*
X7672583Y59047497D01*
X8552223Y59927137D01*
X9028280Y61076441D01*
X9028280Y62320439D01*
X26974280Y62320439D01*
X26974280Y61076441D01*
X27450337Y59927137D01*
X28329977Y59047497D01*
X29479281Y58571440D01*
X30723279Y58571440D01*
X31872583Y59047497D01*
X32752223Y59927137D01*
X33228280Y61076441D01*
X33228280Y62320439D01*
X32905534Y63099619D01*
X52703401Y63099619D01*
X55001280Y60801741D01*
X57299159Y63099619D01*
X56145355Y63453005D01*
X53857205Y63453005D01*
X52703401Y63099619D01*
X32905534Y63099619D01*
X32752223Y63469743D01*
X31872583Y64349383D01*
X30723279Y64825440D01*
X30349094Y64825440D01*
X30476561Y64939276D01*
X29901280Y65514557D01*
X29325999Y64939276D01*
X29461645Y64818135D01*
X28329977Y64349383D01*
X27450337Y63469743D01*
X26974280Y62320439D01*
X9028280Y62320439D01*
X8552223Y63469743D01*
X7672583Y64349383D01*
X6540915Y64818135D01*
X6676561Y64939276D01*
X6101280Y65514557D01*
X5525999Y64939276D01*
X5653466Y64825440D01*
X5279281Y64825440D01*
X4129977Y64349383D01*
X3250337Y63469743D01*
X2774280Y62320439D01*
X-3796720Y62320439D01*
X-3796720Y66150714D01*
X4455851Y66150714D01*
X4486301Y65997631D01*
X4642116Y65823159D01*
X5217397Y66398440D01*
X6985163Y66398440D01*
X7560444Y65823159D01*
X7716259Y65997631D01*
X7746709Y66646166D01*
X7716259Y66799249D01*
X7560444Y66973721D01*
X6985163Y66398440D01*
X5217397Y66398440D01*
X4642116Y66973721D01*
X4486301Y66799249D01*
X4455851Y66150714D01*
X-3796720Y66150714D01*
X-3796720Y67857604D01*
X5525999Y67857604D01*
X6101280Y67282323D01*
X6676561Y67857604D01*
X6502089Y68013419D01*
X5853554Y68043869D01*
X5700471Y68013419D01*
X5525999Y67857604D01*
X-3796720Y67857604D01*
X-3796720Y69139276D01*
X5525999Y69139276D01*
X5700471Y68983461D01*
X6349006Y68953011D01*
X6502089Y68983461D01*
X6676561Y69139276D01*
X6101280Y69714557D01*
X5525999Y69139276D01*
X-3796720Y69139276D01*
X-3796720Y70350714D01*
X4455851Y70350714D01*
X4486301Y70197631D01*
X4642116Y70023159D01*
X5217397Y70598440D01*
X6985163Y70598440D01*
X7560444Y70023159D01*
X7716259Y70197631D01*
X7746709Y70846166D01*
X7716259Y70999249D01*
X7560444Y71173721D01*
X6985163Y70598440D01*
X5217397Y70598440D01*
X4642116Y71173721D01*
X4486301Y70999249D01*
X4455851Y70350714D01*
X-3796720Y70350714D01*
X-3796720Y72057604D01*
X5525999Y72057604D01*
X6101280Y71482323D01*
X6676561Y72057604D01*
X6502089Y72213419D01*
X5853554Y72243869D01*
X5700471Y72213419D01*
X5525999Y72057604D01*
X-3796720Y72057604D01*
X-3796720Y73339276D01*
X5525999Y73339276D01*
X5700471Y73183461D01*
X6349006Y73153011D01*
X6502089Y73183461D01*
X6676561Y73339276D01*
X6101280Y73914557D01*
X5525999Y73339276D01*
X-3796720Y73339276D01*
X-3796720Y74550714D01*
X4455851Y74550714D01*
X4486301Y74397631D01*
X4642116Y74223159D01*
X5217397Y74798440D01*
X6985163Y74798440D01*
X7560444Y74223159D01*
X7716259Y74397631D01*
X7746709Y75046166D01*
X7716259Y75199249D01*
X7560444Y75373721D01*
X6985163Y74798440D01*
X5217397Y74798440D01*
X4642116Y75373721D01*
X4486301Y75199249D01*
X4455851Y74550714D01*
X-3796720Y74550714D01*
X-3796720Y76257604D01*
X5525999Y76257604D01*
X6101280Y75682323D01*
X6676561Y76257604D01*
X6502089Y76413419D01*
X5853554Y76443869D01*
X5700471Y76413419D01*
X5525999Y76257604D01*
X-3796720Y76257604D01*
X-3796720Y77539276D01*
X5525999Y77539276D01*
X5700471Y77383461D01*
X6349006Y77353011D01*
X6502089Y77383461D01*
X6676561Y77539276D01*
X6101280Y78114557D01*
X5525999Y77539276D01*
X-3796720Y77539276D01*
X-3796720Y78750714D01*
X4455851Y78750714D01*
X4486301Y78597631D01*
X4642116Y78423159D01*
X5217397Y78998440D01*
X6985163Y78998440D01*
X7560444Y78423159D01*
X7716259Y78597631D01*
X7746709Y79246166D01*
X7716259Y79399249D01*
X7651953Y79471255D01*
X7924280Y79471255D01*
X7924280Y78525625D01*
X8286157Y77651978D01*
X8954818Y76983317D01*
X9159729Y76898440D01*
X8954818Y76813563D01*
X8286157Y76144902D01*
X7924280Y75271255D01*
X7924280Y74325625D01*
X8286157Y73451978D01*
X8954818Y72783317D01*
X9159729Y72698440D01*
X8954818Y72613563D01*
X8286157Y71944902D01*
X7924280Y71071255D01*
X7924280Y70125625D01*
X8286157Y69251978D01*
X8954818Y68583317D01*
X9159729Y68498440D01*
X8954818Y68413563D01*
X8286157Y67744902D01*
X7924280Y66871255D01*
X7924280Y65925625D01*
X8286157Y65051978D01*
X8954818Y64383317D01*
X9828465Y64021440D01*
X10774095Y64021440D01*
X11647742Y64383317D01*
X12316403Y65051978D01*
X12678280Y65925625D01*
X12678280Y66871255D01*
X12316403Y67744902D01*
X11647742Y68413563D01*
X11442831Y68498440D01*
X11647742Y68583317D01*
X12316403Y69251978D01*
X12678280Y70125625D01*
X12678280Y71071255D01*
X12316403Y71944902D01*
X11647742Y72613563D01*
X11442831Y72698440D01*
X11647742Y72783317D01*
X12316403Y73451978D01*
X12678280Y74325625D01*
X12678280Y75271255D01*
X12316403Y76144902D01*
X11647742Y76813563D01*
X11442831Y76898440D01*
X11647742Y76983317D01*
X12316403Y77651978D01*
X12678280Y78525625D01*
X12678280Y79471255D01*
X23324280Y79471255D01*
X23324280Y78525625D01*
X23686157Y77651978D01*
X24354818Y76983317D01*
X24559729Y76898440D01*
X24354818Y76813563D01*
X23686157Y76144902D01*
X23324280Y75271255D01*
X23324280Y74325625D01*
X23686157Y73451978D01*
X24354818Y72783317D01*
X24559729Y72698440D01*
X24354818Y72613563D01*
X23686157Y71944902D01*
X23324280Y71071255D01*
X23324280Y70125625D01*
X23686157Y69251978D01*
X24354818Y68583317D01*
X24559729Y68498440D01*
X24354818Y68413563D01*
X23686157Y67744902D01*
X23324280Y66871255D01*
X23324280Y65925625D01*
X23686157Y65051978D01*
X24354818Y64383317D01*
X25228465Y64021440D01*
X26174095Y64021440D01*
X27047742Y64383317D01*
X27716403Y65051978D01*
X28078280Y65925625D01*
X28078280Y66150714D01*
X28255851Y66150714D01*
X28286301Y65997631D01*
X28442116Y65823159D01*
X29017397Y66398440D01*
X30785163Y66398440D01*
X31360444Y65823159D01*
X31516259Y65997631D01*
X31546709Y66646166D01*
X31516259Y66799249D01*
X31360444Y66973721D01*
X30785163Y66398440D01*
X29017397Y66398440D01*
X28442116Y66973721D01*
X28286301Y66799249D01*
X28255851Y66150714D01*
X28078280Y66150714D01*
X28078280Y66871255D01*
X27716403Y67744902D01*
X27603701Y67857604D01*
X29325999Y67857604D01*
X29901280Y67282323D01*
X30476561Y67857604D01*
X30302089Y68013419D01*
X29653554Y68043869D01*
X29500471Y68013419D01*
X29325999Y67857604D01*
X27603701Y67857604D01*
X27047742Y68413563D01*
X26842831Y68498440D01*
X27047742Y68583317D01*
X27603701Y69139276D01*
X29325999Y69139276D01*
X29500471Y68983461D01*
X30149006Y68953011D01*
X30302089Y68983461D01*
X30476561Y69139276D01*
X29901280Y69714557D01*
X29325999Y69139276D01*
X27603701Y69139276D01*
X27716403Y69251978D01*
X28078280Y70125625D01*
X28078280Y70350714D01*
X28255851Y70350714D01*
X28286301Y70197631D01*
X28442116Y70023159D01*
X29017397Y70598440D01*
X30785163Y70598440D01*
X31360444Y70023159D01*
X31516259Y70197631D01*
X31525632Y70397261D01*
X52703401Y70397261D01*
X53857205Y70043875D01*
X56145355Y70043875D01*
X57299159Y70397261D01*
X55001280Y72695139D01*
X52703401Y70397261D01*
X31525632Y70397261D01*
X31546709Y70846166D01*
X31516259Y70999249D01*
X31360444Y71173721D01*
X30785163Y70598440D01*
X29017397Y70598440D01*
X28442116Y71173721D01*
X28286301Y70999249D01*
X28255851Y70350714D01*
X28078280Y70350714D01*
X28078280Y71071255D01*
X27716403Y71944902D01*
X27603701Y72057604D01*
X29325999Y72057604D01*
X29901280Y71482323D01*
X30476561Y72057604D01*
X30302089Y72213419D01*
X29653554Y72243869D01*
X29500471Y72213419D01*
X29325999Y72057604D01*
X27603701Y72057604D01*
X27047742Y72613563D01*
X26842831Y72698440D01*
X27047742Y72783317D01*
X27603701Y73339276D01*
X29325999Y73339276D01*
X29500471Y73183461D01*
X30149006Y73153011D01*
X30302089Y73183461D01*
X30476561Y73339276D01*
X29901280Y73914557D01*
X29325999Y73339276D01*
X27603701Y73339276D01*
X27716403Y73451978D01*
X28078280Y74325625D01*
X28078280Y74550714D01*
X28255851Y74550714D01*
X28286301Y74397631D01*
X28442116Y74223159D01*
X29017397Y74798440D01*
X30785163Y74798440D01*
X31360444Y74223159D01*
X31516259Y74397631D01*
X31546709Y75046166D01*
X31516259Y75199249D01*
X31360444Y75373721D01*
X30785163Y74798440D01*
X29017397Y74798440D01*
X28442116Y75373721D01*
X28286301Y75199249D01*
X28255851Y74550714D01*
X28078280Y74550714D01*
X28078280Y75271255D01*
X27716403Y76144902D01*
X27603701Y76257604D01*
X29325999Y76257604D01*
X29901280Y75682323D01*
X30476561Y76257604D01*
X30302089Y76413419D01*
X29653554Y76443869D01*
X29500471Y76413419D01*
X29325999Y76257604D01*
X27603701Y76257604D01*
X27047742Y76813563D01*
X26842831Y76898440D01*
X27047742Y76983317D01*
X27603701Y77539276D01*
X29325999Y77539276D01*
X29500471Y77383461D01*
X30149006Y77353011D01*
X30302089Y77383461D01*
X30476561Y77539276D01*
X29901280Y78114557D01*
X29325999Y77539276D01*
X27603701Y77539276D01*
X27716403Y77651978D01*
X28078280Y78525625D01*
X28078280Y78750714D01*
X28255851Y78750714D01*
X28286301Y78597631D01*
X28442116Y78423159D01*
X29017397Y78998440D01*
X30785163Y78998440D01*
X31360444Y78423159D01*
X31516259Y78597631D01*
X31541842Y79142515D01*
X47046715Y79142515D01*
X47046715Y76854365D01*
X47400101Y75700561D01*
X49697979Y77998440D01*
X60304581Y77998440D01*
X62602459Y75700561D01*
X62955845Y76854365D01*
X62955845Y79142515D01*
X62602459Y80296319D01*
X60304581Y77998440D01*
X49697979Y77998440D01*
X47400101Y80296319D01*
X47046715Y79142515D01*
X31541842Y79142515D01*
X31546709Y79246166D01*
X31516259Y79399249D01*
X31360444Y79573721D01*
X30785163Y78998440D01*
X29017397Y78998440D01*
X28442116Y79573721D01*
X28286301Y79399249D01*
X28255851Y78750714D01*
X28078280Y78750714D01*
X28078280Y79471255D01*
X27716403Y80344902D01*
X27047742Y81013563D01*
X26174095Y81375440D01*
X25228465Y81375440D01*
X24354818Y81013563D01*
X23686157Y80344902D01*
X23324280Y79471255D01*
X12678280Y79471255D01*
X12316403Y80344902D01*
X11647742Y81013563D01*
X10774095Y81375440D01*
X9828465Y81375440D01*
X8954818Y81013563D01*
X8286157Y80344902D01*
X7924280Y79471255D01*
X7651953Y79471255D01*
X7560444Y79573721D01*
X6985163Y78998440D01*
X5217397Y78998440D01*
X4642116Y79573721D01*
X4486301Y79399249D01*
X4455851Y78750714D01*
X-3796720Y78750714D01*
X-3796720Y84320439D01*
X2774280Y84320439D01*
X2774280Y83076441D01*
X3250337Y81927137D01*
X4129977Y81047497D01*
X5279281Y80571440D01*
X5653466Y80571440D01*
X5525999Y80457604D01*
X6101280Y79882323D01*
X6676561Y80457604D01*
X6540915Y80578745D01*
X7672583Y81047497D01*
X8552223Y81927137D01*
X9028280Y83076441D01*
X9028280Y84320439D01*
X26974280Y84320439D01*
X26974280Y83076441D01*
X27450337Y81927137D01*
X28329977Y81047497D01*
X29461645Y80578745D01*
X29325999Y80457604D01*
X29901280Y79882323D01*
X30476561Y80457604D01*
X30349094Y80571440D01*
X30723279Y80571440D01*
X31872583Y81047497D01*
X32752223Y81927137D01*
X33228280Y83076441D01*
X33228280Y84320439D01*
X32752223Y85469743D01*
X32622347Y85599619D01*
X52703401Y85599619D01*
X55001280Y83301741D01*
X57299159Y85599619D01*
X56145355Y85953005D01*
X53857205Y85953005D01*
X52703401Y85599619D01*
X32622347Y85599619D01*
X31872583Y86349383D01*
X30723279Y86825440D01*
X29479281Y86825440D01*
X28329977Y86349383D01*
X27450337Y85469743D01*
X26974280Y84320439D01*
X9028280Y84320439D01*
X8552223Y85469743D01*
X7672583Y86349383D01*
X6523279Y86825440D01*
X5279281Y86825440D01*
X4129977Y86349383D01*
X3250337Y85469743D01*
X2774280Y84320439D01*
X-3796720Y84320439D01*
X-3796720Y90719895D01*
X-3625720Y90719895D01*
X-3625720Y89276985D01*
X-3073542Y87943910D01*
X-2053250Y86923618D01*
X-720175Y86371440D01*
X722735Y86371440D01*
X2055810Y86923618D01*
X3076102Y87943910D01*
X3326506Y88548440D01*
X100194280Y88548440D01*
X100194280Y82758440D01*
X100203947Y82709839D01*
X100231477Y82668637D01*
X100264280Y82646719D01*
X100264280Y6828440D01*
X100273947Y6779839D01*
X100301477Y6738637D01*
X105191477Y1848637D01*
X105232679Y1821107D01*
X105281280Y1811440D01*
X121821280Y1811440D01*
X121869881Y1821107D01*
X121911083Y1848637D01*
X127691083Y7628637D01*
X127718613Y7669839D01*
X127728280Y7718440D01*
X127728280Y87728440D01*
X127719075Y87775910D01*
X127691942Y87817375D01*
X124844709Y90719895D01*
X136374280Y90719895D01*
X136374280Y89276985D01*
X136926458Y87943910D01*
X137946750Y86923618D01*
X139279825Y86371440D01*
X140722735Y86371440D01*
X142055810Y86923618D01*
X143076102Y87943910D01*
X143628280Y89276985D01*
X143628280Y90719895D01*
X143076102Y92052970D01*
X142055810Y93073262D01*
X140722735Y93625440D01*
X139279825Y93625440D01*
X137946750Y93073262D01*
X136926458Y92052970D01*
X136374280Y90719895D01*
X124844709Y90719895D01*
X123571942Y92017375D01*
X123529524Y92045920D01*
X123480894Y92055439D01*
X103730894Y91995439D01*
X103684252Y91986412D01*
X103642686Y91959435D01*
X100232686Y88639435D01*
X100203947Y88597041D01*
X100194280Y88548440D01*
X3326506Y88548440D01*
X3628280Y89276985D01*
X3628280Y90719895D01*
X3076102Y92052970D01*
X2055810Y93073262D01*
X722735Y93625440D01*
X-720175Y93625440D01*
X-2053250Y93073262D01*
X-3073542Y92052970D01*
X-3625720Y90719895D01*
X-3796720Y90719895D01*
X-3796720Y92500556D01*
X-2500835Y93796440D01*
X142503396Y93796440D01*
X143799280Y92500555D01*
X143799280Y92500555D01*
G37*
X143799280Y92500555D02*
X143799281Y-2503674D01*
X142503396Y-3799560D01*
X-2500835Y-3799560D01*
X-3796720Y-2503676D01*
X-3796720Y719895D01*
X-3625720Y719895D01*
X-3625720Y-723015D01*
X-3073542Y-2056090D01*
X-2053250Y-3076382D01*
X-720175Y-3628560D01*
X722735Y-3628560D01*
X2055810Y-3076382D01*
X3076102Y-2056090D01*
X3628280Y-723015D01*
X3628280Y719895D01*
X136374280Y719895D01*
X136374280Y-723015D01*
X136926458Y-2056090D01*
X137946750Y-3076382D01*
X139279825Y-3628560D01*
X140722735Y-3628560D01*
X142055810Y-3076382D01*
X143076102Y-2056090D01*
X143628280Y-723015D01*
X143628280Y719895D01*
X143076102Y2052970D01*
X142055810Y3073262D01*
X140722735Y3625440D01*
X139279825Y3625440D01*
X137946750Y3073262D01*
X136926458Y2052970D01*
X136374280Y719895D01*
X3628280Y719895D01*
X3076102Y2052970D01*
X2231811Y2897261D01*
X52703401Y2897261D01*
X53857205Y2543875D01*
X56145355Y2543875D01*
X57299159Y2897261D01*
X55001280Y5195139D01*
X52703401Y2897261D01*
X2231811Y2897261D01*
X2055810Y3073262D01*
X722735Y3625440D01*
X-720175Y3625440D01*
X-2053250Y3073262D01*
X-3073542Y2052970D01*
X-3625720Y719895D01*
X-3796720Y719895D01*
X-3796720Y25287839D01*
X2774280Y25287839D01*
X2774280Y24043841D01*
X3250337Y22894537D01*
X4129977Y22014897D01*
X4454380Y21880525D01*
X3886157Y21312302D01*
X3524280Y20438655D01*
X3524280Y19493025D01*
X3886157Y18619378D01*
X4554818Y17950717D01*
X4759729Y17865840D01*
X4554818Y17780963D01*
X3886157Y17112302D01*
X3524280Y16238655D01*
X3524280Y15293025D01*
X3886157Y14419378D01*
X4554818Y13750717D01*
X4759729Y13665840D01*
X4554818Y13580963D01*
X3886157Y12912302D01*
X3524280Y12038655D01*
X3524280Y11093025D01*
X3886157Y10219378D01*
X4454380Y9651155D01*
X4129977Y9516783D01*
X3250337Y8637143D01*
X2774280Y7487839D01*
X2774280Y6243841D01*
X3250337Y5094537D01*
X4129977Y4214897D01*
X5279281Y3738840D01*
X6523279Y3738840D01*
X7672583Y4214897D01*
X8552223Y5094537D01*
X9028280Y6243841D01*
X9028280Y7487839D01*
X8552223Y8637143D01*
X7672583Y9516783D01*
X7348180Y9651155D01*
X7803701Y10106676D01*
X9525999Y10106676D01*
X9700471Y9950861D01*
X10349006Y9920411D01*
X10502089Y9950861D01*
X10676561Y10106676D01*
X25325999Y10106676D01*
X25500471Y9950861D01*
X26149006Y9920411D01*
X26302089Y9950861D01*
X26476561Y10106676D01*
X25901280Y10681957D01*
X25325999Y10106676D01*
X10676561Y10106676D01*
X10101280Y10681957D01*
X9525999Y10106676D01*
X7803701Y10106676D01*
X7916403Y10219378D01*
X8278280Y11093025D01*
X8278280Y11318114D01*
X8455851Y11318114D01*
X8486301Y11165031D01*
X8642116Y10990559D01*
X9217397Y11565840D01*
X10985163Y11565840D01*
X11560444Y10990559D01*
X11716259Y11165031D01*
X11723446Y11318114D01*
X24255851Y11318114D01*
X24286301Y11165031D01*
X24442116Y10990559D01*
X25017397Y11565840D01*
X26785163Y11565840D01*
X27360444Y10990559D01*
X27516259Y11165031D01*
X27546709Y11813566D01*
X27516259Y11966649D01*
X27360444Y12141121D01*
X26785163Y11565840D01*
X25017397Y11565840D01*
X24442116Y12141121D01*
X24286301Y11966649D01*
X24255851Y11318114D01*
X11723446Y11318114D01*
X11746709Y11813566D01*
X11716259Y11966649D01*
X11560444Y12141121D01*
X10985163Y11565840D01*
X9217397Y11565840D01*
X8642116Y12141121D01*
X8486301Y11966649D01*
X8455851Y11318114D01*
X8278280Y11318114D01*
X8278280Y12038655D01*
X7916403Y12912302D01*
X7803701Y13025004D01*
X9525999Y13025004D01*
X10101280Y12449723D01*
X10676561Y13025004D01*
X25325999Y13025004D01*
X25901280Y12449723D01*
X26476561Y13025004D01*
X26302089Y13180819D01*
X25653554Y13211269D01*
X25500471Y13180819D01*
X25325999Y13025004D01*
X10676561Y13025004D01*
X10502089Y13180819D01*
X9853554Y13211269D01*
X9700471Y13180819D01*
X9525999Y13025004D01*
X7803701Y13025004D01*
X7247742Y13580963D01*
X7042831Y13665840D01*
X7247742Y13750717D01*
X7803701Y14306676D01*
X9525999Y14306676D01*
X9700471Y14150861D01*
X10349006Y14120411D01*
X10502089Y14150861D01*
X10676561Y14306676D01*
X25325999Y14306676D01*
X25500471Y14150861D01*
X26149006Y14120411D01*
X26302089Y14150861D01*
X26476561Y14306676D01*
X25901280Y14881957D01*
X25325999Y14306676D01*
X10676561Y14306676D01*
X10101280Y14881957D01*
X9525999Y14306676D01*
X7803701Y14306676D01*
X7916403Y14419378D01*
X8278280Y15293025D01*
X8278280Y15518114D01*
X8455851Y15518114D01*
X8486301Y15365031D01*
X8642116Y15190559D01*
X9217397Y15765840D01*
X10985163Y15765840D01*
X11560444Y15190559D01*
X11716259Y15365031D01*
X11723446Y15518114D01*
X24255851Y15518114D01*
X24286301Y15365031D01*
X24442116Y15190559D01*
X25017397Y15765840D01*
X26785163Y15765840D01*
X27360444Y15190559D01*
X27516259Y15365031D01*
X27546709Y16013566D01*
X27516259Y16166649D01*
X27360444Y16341121D01*
X26785163Y15765840D01*
X25017397Y15765840D01*
X24442116Y16341121D01*
X24286301Y16166649D01*
X24255851Y15518114D01*
X11723446Y15518114D01*
X11746709Y16013566D01*
X11716259Y16166649D01*
X11560444Y16341121D01*
X10985163Y15765840D01*
X9217397Y15765840D01*
X8642116Y16341121D01*
X8486301Y16166649D01*
X8455851Y15518114D01*
X8278280Y15518114D01*
X8278280Y16238655D01*
X7916403Y17112302D01*
X7803701Y17225004D01*
X9525999Y17225004D01*
X10101280Y16649723D01*
X10676561Y17225004D01*
X25325999Y17225004D01*
X25901280Y16649723D01*
X26476561Y17225004D01*
X26302089Y17380819D01*
X25653554Y17411269D01*
X25500471Y17380819D01*
X25325999Y17225004D01*
X10676561Y17225004D01*
X10502089Y17380819D01*
X9853554Y17411269D01*
X9700471Y17380819D01*
X9525999Y17225004D01*
X7803701Y17225004D01*
X7247742Y17780963D01*
X7042831Y17865840D01*
X7247742Y17950717D01*
X7803701Y18506676D01*
X9525999Y18506676D01*
X9700471Y18350861D01*
X10349006Y18320411D01*
X10502089Y18350861D01*
X10676561Y18506676D01*
X25325999Y18506676D01*
X25500471Y18350861D01*
X26149006Y18320411D01*
X26302089Y18350861D01*
X26476561Y18506676D01*
X25901280Y19081957D01*
X25325999Y18506676D01*
X10676561Y18506676D01*
X10101280Y19081957D01*
X9525999Y18506676D01*
X7803701Y18506676D01*
X7916403Y18619378D01*
X8278280Y19493025D01*
X8278280Y19718114D01*
X8455851Y19718114D01*
X8486301Y19565031D01*
X8642116Y19390559D01*
X9217397Y19965840D01*
X10985163Y19965840D01*
X11560444Y19390559D01*
X11716259Y19565031D01*
X11723446Y19718114D01*
X24255851Y19718114D01*
X24286301Y19565031D01*
X24442116Y19390559D01*
X25017397Y19965840D01*
X26785163Y19965840D01*
X27360444Y19390559D01*
X27516259Y19565031D01*
X27546709Y20213566D01*
X27516259Y20366649D01*
X27360444Y20541121D01*
X26785163Y19965840D01*
X25017397Y19965840D01*
X24442116Y20541121D01*
X24286301Y20366649D01*
X24255851Y19718114D01*
X11723446Y19718114D01*
X11746709Y20213566D01*
X11716259Y20366649D01*
X11560444Y20541121D01*
X10985163Y19965840D01*
X9217397Y19965840D01*
X8642116Y20541121D01*
X8486301Y20366649D01*
X8455851Y19718114D01*
X8278280Y19718114D01*
X8278280Y20438655D01*
X7916403Y21312302D01*
X7803701Y21425004D01*
X9525999Y21425004D01*
X10101280Y20849723D01*
X10676561Y21425004D01*
X25325999Y21425004D01*
X25901280Y20849723D01*
X26476561Y21425004D01*
X26302089Y21580819D01*
X25653554Y21611269D01*
X25500471Y21580819D01*
X25325999Y21425004D01*
X10676561Y21425004D01*
X10502089Y21580819D01*
X9853554Y21611269D01*
X9700471Y21580819D01*
X9525999Y21425004D01*
X7803701Y21425004D01*
X7348180Y21880525D01*
X7672583Y22014897D01*
X8552223Y22894537D01*
X9028280Y24043841D01*
X9028280Y25287839D01*
X26974280Y25287839D01*
X26974280Y24043841D01*
X27450337Y22894537D01*
X28329977Y22014897D01*
X28654380Y21880525D01*
X28086157Y21312302D01*
X27724280Y20438655D01*
X27724280Y19493025D01*
X28086157Y18619378D01*
X28754818Y17950717D01*
X28959729Y17865840D01*
X28754818Y17780963D01*
X28086157Y17112302D01*
X27724280Y16238655D01*
X27724280Y15293025D01*
X28086157Y14419378D01*
X28754818Y13750717D01*
X28959729Y13665840D01*
X28754818Y13580963D01*
X28086157Y12912302D01*
X27724280Y12038655D01*
X27724280Y11093025D01*
X28086157Y10219378D01*
X28654380Y9651155D01*
X28329977Y9516783D01*
X27450337Y8637143D01*
X26974280Y7487839D01*
X26974280Y6243841D01*
X27450337Y5094537D01*
X28329977Y4214897D01*
X29479281Y3738840D01*
X30723279Y3738840D01*
X31872583Y4214897D01*
X32752223Y5094537D01*
X33228280Y6243841D01*
X33228280Y7487839D01*
X32752223Y8637143D01*
X31872583Y9516783D01*
X31548180Y9651155D01*
X32116403Y10219378D01*
X32478280Y11093025D01*
X32478280Y11642515D01*
X47046715Y11642515D01*
X47046715Y9354365D01*
X47400101Y8200561D01*
X49697979Y10498440D01*
X60304581Y10498440D01*
X62602459Y8200561D01*
X62955845Y9354365D01*
X62955845Y11642515D01*
X62602459Y12796319D01*
X60304581Y10498440D01*
X49697979Y10498440D01*
X47400101Y12796319D01*
X47046715Y11642515D01*
X32478280Y11642515D01*
X32478280Y12038655D01*
X32116403Y12912302D01*
X31447742Y13580963D01*
X31242831Y13665840D01*
X31447742Y13750717D01*
X32116403Y14419378D01*
X32478280Y15293025D01*
X32478280Y16238655D01*
X32116403Y17112302D01*
X31447742Y17780963D01*
X31242831Y17865840D01*
X31447742Y17950717D01*
X31596644Y18099619D01*
X52703401Y18099619D01*
X55001280Y15801741D01*
X57299159Y18099619D01*
X56145355Y18453005D01*
X53857205Y18453005D01*
X52703401Y18099619D01*
X31596644Y18099619D01*
X32116403Y18619378D01*
X32478280Y19493025D01*
X32478280Y20438655D01*
X32116403Y21312302D01*
X31548180Y21880525D01*
X31872583Y22014897D01*
X32752223Y22894537D01*
X33228280Y24043841D01*
X33228280Y25287839D01*
X33182956Y25397261D01*
X52703401Y25397261D01*
X53857205Y25043875D01*
X56145355Y25043875D01*
X57299159Y25397261D01*
X55001280Y27695139D01*
X52703401Y25397261D01*
X33182956Y25397261D01*
X32752223Y26437143D01*
X31872583Y27316783D01*
X30723279Y27792840D01*
X29479281Y27792840D01*
X28329977Y27316783D01*
X27450337Y26437143D01*
X26974280Y25287839D01*
X9028280Y25287839D01*
X8552223Y26437143D01*
X7672583Y27316783D01*
X6523279Y27792840D01*
X5279281Y27792840D01*
X4129977Y27316783D01*
X3250337Y26437143D01*
X2774280Y25287839D01*
X-3796720Y25287839D01*
X-3796720Y54120439D01*
X2774280Y54120439D01*
X2774280Y52876441D01*
X3250337Y51727137D01*
X4129977Y50847497D01*
X4454380Y50713125D01*
X3886157Y50144902D01*
X3524280Y49271255D01*
X3524280Y48325625D01*
X3886157Y47451978D01*
X4554818Y46783317D01*
X4759729Y46698440D01*
X4554818Y46613563D01*
X3886157Y45944902D01*
X3524280Y45071255D01*
X3524280Y44125625D01*
X3886157Y43251978D01*
X4554818Y42583317D01*
X4759729Y42498440D01*
X4554818Y42413563D01*
X3886157Y41744902D01*
X3524280Y40871255D01*
X3524280Y39925625D01*
X3886157Y39051978D01*
X4454380Y38483755D01*
X4129977Y38349383D01*
X3250337Y37469743D01*
X2774280Y36320439D01*
X2774280Y35076441D01*
X3250337Y33927137D01*
X4129977Y33047497D01*
X5279281Y32571440D01*
X6523279Y32571440D01*
X7672583Y33047497D01*
X8552223Y33927137D01*
X9028280Y35076441D01*
X9028280Y36320439D01*
X8552223Y37469743D01*
X7672583Y38349383D01*
X7348180Y38483755D01*
X7803701Y38939276D01*
X9525999Y38939276D01*
X9700471Y38783461D01*
X10349006Y38753011D01*
X10502089Y38783461D01*
X10676561Y38939276D01*
X25325999Y38939276D01*
X25500471Y38783461D01*
X26149006Y38753011D01*
X26302089Y38783461D01*
X26476561Y38939276D01*
X25901280Y39514557D01*
X25325999Y38939276D01*
X10676561Y38939276D01*
X10101280Y39514557D01*
X9525999Y38939276D01*
X7803701Y38939276D01*
X7916403Y39051978D01*
X8278280Y39925625D01*
X8278280Y40150714D01*
X8455851Y40150714D01*
X8486301Y39997631D01*
X8642116Y39823159D01*
X9217397Y40398440D01*
X10985163Y40398440D01*
X11560444Y39823159D01*
X11716259Y39997631D01*
X11723446Y40150714D01*
X24255851Y40150714D01*
X24286301Y39997631D01*
X24442116Y39823159D01*
X25017397Y40398440D01*
X26785163Y40398440D01*
X27360444Y39823159D01*
X27516259Y39997631D01*
X27546709Y40646166D01*
X27516259Y40799249D01*
X27360444Y40973721D01*
X26785163Y40398440D01*
X25017397Y40398440D01*
X24442116Y40973721D01*
X24286301Y40799249D01*
X24255851Y40150714D01*
X11723446Y40150714D01*
X11746709Y40646166D01*
X11716259Y40799249D01*
X11560444Y40973721D01*
X10985163Y40398440D01*
X9217397Y40398440D01*
X8642116Y40973721D01*
X8486301Y40799249D01*
X8455851Y40150714D01*
X8278280Y40150714D01*
X8278280Y40871255D01*
X7916403Y41744902D01*
X7803701Y41857604D01*
X9525999Y41857604D01*
X10101280Y41282323D01*
X10676561Y41857604D01*
X25325999Y41857604D01*
X25901280Y41282323D01*
X26476561Y41857604D01*
X26302089Y42013419D01*
X25653554Y42043869D01*
X25500471Y42013419D01*
X25325999Y41857604D01*
X10676561Y41857604D01*
X10502089Y42013419D01*
X9853554Y42043869D01*
X9700471Y42013419D01*
X9525999Y41857604D01*
X7803701Y41857604D01*
X7247742Y42413563D01*
X7042831Y42498440D01*
X7247742Y42583317D01*
X7803701Y43139276D01*
X9525999Y43139276D01*
X9700471Y42983461D01*
X10349006Y42953011D01*
X10502089Y42983461D01*
X10676561Y43139276D01*
X25325999Y43139276D01*
X25500471Y42983461D01*
X26149006Y42953011D01*
X26302089Y42983461D01*
X26476561Y43139276D01*
X25901280Y43714557D01*
X25325999Y43139276D01*
X10676561Y43139276D01*
X10101280Y43714557D01*
X9525999Y43139276D01*
X7803701Y43139276D01*
X7916403Y43251978D01*
X8278280Y44125625D01*
X8278280Y44350714D01*
X8455851Y44350714D01*
X8486301Y44197631D01*
X8642116Y44023159D01*
X9217397Y44598440D01*
X10985163Y44598440D01*
X11560444Y44023159D01*
X11716259Y44197631D01*
X11723446Y44350714D01*
X24255851Y44350714D01*
X24286301Y44197631D01*
X24442116Y44023159D01*
X25017397Y44598440D01*
X26785163Y44598440D01*
X27360444Y44023159D01*
X27516259Y44197631D01*
X27546709Y44846166D01*
X27516259Y44999249D01*
X27360444Y45173721D01*
X26785163Y44598440D01*
X25017397Y44598440D01*
X24442116Y45173721D01*
X24286301Y44999249D01*
X24255851Y44350714D01*
X11723446Y44350714D01*
X11746709Y44846166D01*
X11716259Y44999249D01*
X11560444Y45173721D01*
X10985163Y44598440D01*
X9217397Y44598440D01*
X8642116Y45173721D01*
X8486301Y44999249D01*
X8455851Y44350714D01*
X8278280Y44350714D01*
X8278280Y45071255D01*
X7916403Y45944902D01*
X7803701Y46057604D01*
X9525999Y46057604D01*
X10101280Y45482323D01*
X10676561Y46057604D01*
X25325999Y46057604D01*
X25901280Y45482323D01*
X26476561Y46057604D01*
X26302089Y46213419D01*
X25653554Y46243869D01*
X25500471Y46213419D01*
X25325999Y46057604D01*
X10676561Y46057604D01*
X10502089Y46213419D01*
X9853554Y46243869D01*
X9700471Y46213419D01*
X9525999Y46057604D01*
X7803701Y46057604D01*
X7247742Y46613563D01*
X7042831Y46698440D01*
X7247742Y46783317D01*
X7803701Y47339276D01*
X9525999Y47339276D01*
X9700471Y47183461D01*
X10349006Y47153011D01*
X10502089Y47183461D01*
X10676561Y47339276D01*
X25325999Y47339276D01*
X25500471Y47183461D01*
X26149006Y47153011D01*
X26302089Y47183461D01*
X26476561Y47339276D01*
X25901280Y47914557D01*
X25325999Y47339276D01*
X10676561Y47339276D01*
X10101280Y47914557D01*
X9525999Y47339276D01*
X7803701Y47339276D01*
X7916403Y47451978D01*
X8278280Y48325625D01*
X8278280Y48550714D01*
X8455851Y48550714D01*
X8486301Y48397631D01*
X8642116Y48223159D01*
X9217397Y48798440D01*
X10985163Y48798440D01*
X11560444Y48223159D01*
X11716259Y48397631D01*
X11723446Y48550714D01*
X24255851Y48550714D01*
X24286301Y48397631D01*
X24442116Y48223159D01*
X25017397Y48798440D01*
X26785163Y48798440D01*
X27360444Y48223159D01*
X27516259Y48397631D01*
X27546709Y49046166D01*
X27516259Y49199249D01*
X27360444Y49373721D01*
X26785163Y48798440D01*
X25017397Y48798440D01*
X24442116Y49373721D01*
X24286301Y49199249D01*
X24255851Y48550714D01*
X11723446Y48550714D01*
X11746709Y49046166D01*
X11716259Y49199249D01*
X11560444Y49373721D01*
X10985163Y48798440D01*
X9217397Y48798440D01*
X8642116Y49373721D01*
X8486301Y49199249D01*
X8455851Y48550714D01*
X8278280Y48550714D01*
X8278280Y49271255D01*
X7916403Y50144902D01*
X7803701Y50257604D01*
X9525999Y50257604D01*
X10101280Y49682323D01*
X10676561Y50257604D01*
X25325999Y50257604D01*
X25901280Y49682323D01*
X26476561Y50257604D01*
X26302089Y50413419D01*
X25653554Y50443869D01*
X25500471Y50413419D01*
X25325999Y50257604D01*
X10676561Y50257604D01*
X10502089Y50413419D01*
X9853554Y50443869D01*
X9700471Y50413419D01*
X9525999Y50257604D01*
X7803701Y50257604D01*
X7348180Y50713125D01*
X7672583Y50847497D01*
X8552223Y51727137D01*
X9028280Y52876441D01*
X9028280Y54120439D01*
X26974280Y54120439D01*
X26974280Y52876441D01*
X27450337Y51727137D01*
X28329977Y50847497D01*
X28654380Y50713125D01*
X28086157Y50144902D01*
X27724280Y49271255D01*
X27724280Y48325625D01*
X28086157Y47451978D01*
X28754818Y46783317D01*
X28959729Y46698440D01*
X28754818Y46613563D01*
X28086157Y45944902D01*
X27724280Y45071255D01*
X27724280Y44125625D01*
X28086157Y43251978D01*
X28754818Y42583317D01*
X28959729Y42498440D01*
X28754818Y42413563D01*
X28086157Y41744902D01*
X27724280Y40871255D01*
X27724280Y39925625D01*
X28086157Y39051978D01*
X28654380Y38483755D01*
X28329977Y38349383D01*
X27450337Y37469743D01*
X26974280Y36320439D01*
X26974280Y35076441D01*
X27450337Y33927137D01*
X28329977Y33047497D01*
X29479281Y32571440D01*
X30723279Y32571440D01*
X31872583Y33047497D01*
X32752223Y33927137D01*
X32841435Y34142515D01*
X47046715Y34142515D01*
X47046715Y31854365D01*
X47400101Y30700561D01*
X49697979Y32998440D01*
X60304581Y32998440D01*
X62602459Y30700561D01*
X62955845Y31854365D01*
X62955845Y34142515D01*
X62602459Y35296319D01*
X60304581Y32998440D01*
X49697979Y32998440D01*
X47400101Y35296319D01*
X47046715Y34142515D01*
X32841435Y34142515D01*
X33228280Y35076441D01*
X33228280Y36320439D01*
X32752223Y37469743D01*
X31872583Y38349383D01*
X31548180Y38483755D01*
X32116403Y39051978D01*
X32478280Y39925625D01*
X32478280Y40599619D01*
X52703401Y40599619D01*
X55001280Y38301741D01*
X57299159Y40599619D01*
X56145355Y40953005D01*
X53857205Y40953005D01*
X52703401Y40599619D01*
X32478280Y40599619D01*
X32478280Y40871255D01*
X32116403Y41744902D01*
X31447742Y42413563D01*
X31242831Y42498440D01*
X31447742Y42583317D01*
X32116403Y43251978D01*
X32478280Y44125625D01*
X32478280Y45071255D01*
X32116403Y45944902D01*
X31447742Y46613563D01*
X31242831Y46698440D01*
X31447742Y46783317D01*
X32116403Y47451978D01*
X32300845Y47897261D01*
X52703401Y47897261D01*
X53857205Y47543875D01*
X56145355Y47543875D01*
X57299159Y47897261D01*
X55001280Y50195139D01*
X52703401Y47897261D01*
X32300845Y47897261D01*
X32478280Y48325625D01*
X32478280Y49271255D01*
X32116403Y50144902D01*
X31548180Y50713125D01*
X31872583Y50847497D01*
X32752223Y51727137D01*
X33228280Y52876441D01*
X33228280Y54120439D01*
X32752223Y55269743D01*
X31872583Y56149383D01*
X30723279Y56625440D01*
X29479281Y56625440D01*
X28329977Y56149383D01*
X27450337Y55269743D01*
X26974280Y54120439D01*
X9028280Y54120439D01*
X8552223Y55269743D01*
X7672583Y56149383D01*
X6523279Y56625440D01*
X5279281Y56625440D01*
X4129977Y56149383D01*
X3250337Y55269743D01*
X2774280Y54120439D01*
X-3796720Y54120439D01*
X-3796720Y56642515D01*
X47046715Y56642515D01*
X47046715Y54354365D01*
X47400101Y53200561D01*
X49697979Y55498440D01*
X60304581Y55498440D01*
X62602459Y53200561D01*
X62955845Y54354365D01*
X62955845Y56642515D01*
X62602459Y57796319D01*
X60304581Y55498440D01*
X49697979Y55498440D01*
X47400101Y57796319D01*
X47046715Y56642515D01*
X-3796720Y56642515D01*
X-3796720Y62320439D01*
X2774280Y62320439D01*
X2774280Y61076441D01*
X3250337Y59927137D01*
X4129977Y59047497D01*
X5279281Y58571440D01*
X6523279Y58571440D01*
X7672583Y59047497D01*
X8552223Y59927137D01*
X9028280Y61076441D01*
X9028280Y62320439D01*
X26974280Y62320439D01*
X26974280Y61076441D01*
X27450337Y59927137D01*
X28329977Y59047497D01*
X29479281Y58571440D01*
X30723279Y58571440D01*
X31872583Y59047497D01*
X32752223Y59927137D01*
X33228280Y61076441D01*
X33228280Y62320439D01*
X32905534Y63099619D01*
X52703401Y63099619D01*
X55001280Y60801741D01*
X57299159Y63099619D01*
X56145355Y63453005D01*
X53857205Y63453005D01*
X52703401Y63099619D01*
X32905534Y63099619D01*
X32752223Y63469743D01*
X31872583Y64349383D01*
X30723279Y64825440D01*
X30349094Y64825440D01*
X30476561Y64939276D01*
X29901280Y65514557D01*
X29325999Y64939276D01*
X29461645Y64818135D01*
X28329977Y64349383D01*
X27450337Y63469743D01*
X26974280Y62320439D01*
X9028280Y62320439D01*
X8552223Y63469743D01*
X7672583Y64349383D01*
X6540915Y64818135D01*
X6676561Y64939276D01*
X6101280Y65514557D01*
X5525999Y64939276D01*
X5653466Y64825440D01*
X5279281Y64825440D01*
X4129977Y64349383D01*
X3250337Y63469743D01*
X2774280Y62320439D01*
X-3796720Y62320439D01*
X-3796720Y66150714D01*
X4455851Y66150714D01*
X4486301Y65997631D01*
X4642116Y65823159D01*
X5217397Y66398440D01*
X6985163Y66398440D01*
X7560444Y65823159D01*
X7716259Y65997631D01*
X7746709Y66646166D01*
X7716259Y66799249D01*
X7560444Y66973721D01*
X6985163Y66398440D01*
X5217397Y66398440D01*
X4642116Y66973721D01*
X4486301Y66799249D01*
X4455851Y66150714D01*
X-3796720Y66150714D01*
X-3796720Y67857604D01*
X5525999Y67857604D01*
X6101280Y67282323D01*
X6676561Y67857604D01*
X6502089Y68013419D01*
X5853554Y68043869D01*
X5700471Y68013419D01*
X5525999Y67857604D01*
X-3796720Y67857604D01*
X-3796720Y69139276D01*
X5525999Y69139276D01*
X5700471Y68983461D01*
X6349006Y68953011D01*
X6502089Y68983461D01*
X6676561Y69139276D01*
X6101280Y69714557D01*
X5525999Y69139276D01*
X-3796720Y69139276D01*
X-3796720Y70350714D01*
X4455851Y70350714D01*
X4486301Y70197631D01*
X4642116Y70023159D01*
X5217397Y70598440D01*
X6985163Y70598440D01*
X7560444Y70023159D01*
X7716259Y70197631D01*
X7746709Y70846166D01*
X7716259Y70999249D01*
X7560444Y71173721D01*
X6985163Y70598440D01*
X5217397Y70598440D01*
X4642116Y71173721D01*
X4486301Y70999249D01*
X4455851Y70350714D01*
X-3796720Y70350714D01*
X-3796720Y72057604D01*
X5525999Y72057604D01*
X6101280Y71482323D01*
X6676561Y72057604D01*
X6502089Y72213419D01*
X5853554Y72243869D01*
X5700471Y72213419D01*
X5525999Y72057604D01*
X-3796720Y72057604D01*
X-3796720Y73339276D01*
X5525999Y73339276D01*
X5700471Y73183461D01*
X6349006Y73153011D01*
X6502089Y73183461D01*
X6676561Y73339276D01*
X6101280Y73914557D01*
X5525999Y73339276D01*
X-3796720Y73339276D01*
X-3796720Y74550714D01*
X4455851Y74550714D01*
X4486301Y74397631D01*
X4642116Y74223159D01*
X5217397Y74798440D01*
X6985163Y74798440D01*
X7560444Y74223159D01*
X7716259Y74397631D01*
X7746709Y75046166D01*
X7716259Y75199249D01*
X7560444Y75373721D01*
X6985163Y74798440D01*
X5217397Y74798440D01*
X4642116Y75373721D01*
X4486301Y75199249D01*
X4455851Y74550714D01*
X-3796720Y74550714D01*
X-3796720Y76257604D01*
X5525999Y76257604D01*
X6101280Y75682323D01*
X6676561Y76257604D01*
X6502089Y76413419D01*
X5853554Y76443869D01*
X5700471Y76413419D01*
X5525999Y76257604D01*
X-3796720Y76257604D01*
X-3796720Y77539276D01*
X5525999Y77539276D01*
X5700471Y77383461D01*
X6349006Y77353011D01*
X6502089Y77383461D01*
X6676561Y77539276D01*
X6101280Y78114557D01*
X5525999Y77539276D01*
X-3796720Y77539276D01*
X-3796720Y78750714D01*
X4455851Y78750714D01*
X4486301Y78597631D01*
X4642116Y78423159D01*
X5217397Y78998440D01*
X6985163Y78998440D01*
X7560444Y78423159D01*
X7716259Y78597631D01*
X7746709Y79246166D01*
X7716259Y79399249D01*
X7651953Y79471255D01*
X7924280Y79471255D01*
X7924280Y78525625D01*
X8286157Y77651978D01*
X8954818Y76983317D01*
X9159729Y76898440D01*
X8954818Y76813563D01*
X8286157Y76144902D01*
X7924280Y75271255D01*
X7924280Y74325625D01*
X8286157Y73451978D01*
X8954818Y72783317D01*
X9159729Y72698440D01*
X8954818Y72613563D01*
X8286157Y71944902D01*
X7924280Y71071255D01*
X7924280Y70125625D01*
X8286157Y69251978D01*
X8954818Y68583317D01*
X9159729Y68498440D01*
X8954818Y68413563D01*
X8286157Y67744902D01*
X7924280Y66871255D01*
X7924280Y65925625D01*
X8286157Y65051978D01*
X8954818Y64383317D01*
X9828465Y64021440D01*
X10774095Y64021440D01*
X11647742Y64383317D01*
X12316403Y65051978D01*
X12678280Y65925625D01*
X12678280Y66871255D01*
X12316403Y67744902D01*
X11647742Y68413563D01*
X11442831Y68498440D01*
X11647742Y68583317D01*
X12316403Y69251978D01*
X12678280Y70125625D01*
X12678280Y71071255D01*
X12316403Y71944902D01*
X11647742Y72613563D01*
X11442831Y72698440D01*
X11647742Y72783317D01*
X12316403Y73451978D01*
X12678280Y74325625D01*
X12678280Y75271255D01*
X12316403Y76144902D01*
X11647742Y76813563D01*
X11442831Y76898440D01*
X11647742Y76983317D01*
X12316403Y77651978D01*
X12678280Y78525625D01*
X12678280Y79471255D01*
X23324280Y79471255D01*
X23324280Y78525625D01*
X23686157Y77651978D01*
X24354818Y76983317D01*
X24559729Y76898440D01*
X24354818Y76813563D01*
X23686157Y76144902D01*
X23324280Y75271255D01*
X23324280Y74325625D01*
X23686157Y73451978D01*
X24354818Y72783317D01*
X24559729Y72698440D01*
X24354818Y72613563D01*
X23686157Y71944902D01*
X23324280Y71071255D01*
X23324280Y70125625D01*
X23686157Y69251978D01*
X24354818Y68583317D01*
X24559729Y68498440D01*
X24354818Y68413563D01*
X23686157Y67744902D01*
X23324280Y66871255D01*
X23324280Y65925625D01*
X23686157Y65051978D01*
X24354818Y64383317D01*
X25228465Y64021440D01*
X26174095Y64021440D01*
X27047742Y64383317D01*
X27716403Y65051978D01*
X28078280Y65925625D01*
X28078280Y66150714D01*
X28255851Y66150714D01*
X28286301Y65997631D01*
X28442116Y65823159D01*
X29017397Y66398440D01*
X30785163Y66398440D01*
X31360444Y65823159D01*
X31516259Y65997631D01*
X31546709Y66646166D01*
X31516259Y66799249D01*
X31360444Y66973721D01*
X30785163Y66398440D01*
X29017397Y66398440D01*
X28442116Y66973721D01*
X28286301Y66799249D01*
X28255851Y66150714D01*
X28078280Y66150714D01*
X28078280Y66871255D01*
X27716403Y67744902D01*
X27603701Y67857604D01*
X29325999Y67857604D01*
X29901280Y67282323D01*
X30476561Y67857604D01*
X30302089Y68013419D01*
X29653554Y68043869D01*
X29500471Y68013419D01*
X29325999Y67857604D01*
X27603701Y67857604D01*
X27047742Y68413563D01*
X26842831Y68498440D01*
X27047742Y68583317D01*
X27603701Y69139276D01*
X29325999Y69139276D01*
X29500471Y68983461D01*
X30149006Y68953011D01*
X30302089Y68983461D01*
X30476561Y69139276D01*
X29901280Y69714557D01*
X29325999Y69139276D01*
X27603701Y69139276D01*
X27716403Y69251978D01*
X28078280Y70125625D01*
X28078280Y70350714D01*
X28255851Y70350714D01*
X28286301Y70197631D01*
X28442116Y70023159D01*
X29017397Y70598440D01*
X30785163Y70598440D01*
X31360444Y70023159D01*
X31516259Y70197631D01*
X31525632Y70397261D01*
X52703401Y70397261D01*
X53857205Y70043875D01*
X56145355Y70043875D01*
X57299159Y70397261D01*
X55001280Y72695139D01*
X52703401Y70397261D01*
X31525632Y70397261D01*
X31546709Y70846166D01*
X31516259Y70999249D01*
X31360444Y71173721D01*
X30785163Y70598440D01*
X29017397Y70598440D01*
X28442116Y71173721D01*
X28286301Y70999249D01*
X28255851Y70350714D01*
X28078280Y70350714D01*
X28078280Y71071255D01*
X27716403Y71944902D01*
X27603701Y72057604D01*
X29325999Y72057604D01*
X29901280Y71482323D01*
X30476561Y72057604D01*
X30302089Y72213419D01*
X29653554Y72243869D01*
X29500471Y72213419D01*
X29325999Y72057604D01*
X27603701Y72057604D01*
X27047742Y72613563D01*
X26842831Y72698440D01*
X27047742Y72783317D01*
X27603701Y73339276D01*
X29325999Y73339276D01*
X29500471Y73183461D01*
X30149006Y73153011D01*
X30302089Y73183461D01*
X30476561Y73339276D01*
X29901280Y73914557D01*
X29325999Y73339276D01*
X27603701Y73339276D01*
X27716403Y73451978D01*
X28078280Y74325625D01*
X28078280Y74550714D01*
X28255851Y74550714D01*
X28286301Y74397631D01*
X28442116Y74223159D01*
X29017397Y74798440D01*
X30785163Y74798440D01*
X31360444Y74223159D01*
X31516259Y74397631D01*
X31546709Y75046166D01*
X31516259Y75199249D01*
X31360444Y75373721D01*
X30785163Y74798440D01*
X29017397Y74798440D01*
X28442116Y75373721D01*
X28286301Y75199249D01*
X28255851Y74550714D01*
X28078280Y74550714D01*
X28078280Y75271255D01*
X27716403Y76144902D01*
X27603701Y76257604D01*
X29325999Y76257604D01*
X29901280Y75682323D01*
X30476561Y76257604D01*
X30302089Y76413419D01*
X29653554Y76443869D01*
X29500471Y76413419D01*
X29325999Y76257604D01*
X27603701Y76257604D01*
X27047742Y76813563D01*
X26842831Y76898440D01*
X27047742Y76983317D01*
X27603701Y77539276D01*
X29325999Y77539276D01*
X29500471Y77383461D01*
X30149006Y77353011D01*
X30302089Y77383461D01*
X30476561Y77539276D01*
X29901280Y78114557D01*
X29325999Y77539276D01*
X27603701Y77539276D01*
X27716403Y77651978D01*
X28078280Y78525625D01*
X28078280Y78750714D01*
X28255851Y78750714D01*
X28286301Y78597631D01*
X28442116Y78423159D01*
X29017397Y78998440D01*
X30785163Y78998440D01*
X31360444Y78423159D01*
X31516259Y78597631D01*
X31541842Y79142515D01*
X47046715Y79142515D01*
X47046715Y76854365D01*
X47400101Y75700561D01*
X49697979Y77998440D01*
X60304581Y77998440D01*
X62602459Y75700561D01*
X62955845Y76854365D01*
X62955845Y79142515D01*
X62602459Y80296319D01*
X60304581Y77998440D01*
X49697979Y77998440D01*
X47400101Y80296319D01*
X47046715Y79142515D01*
X31541842Y79142515D01*
X31546709Y79246166D01*
X31516259Y79399249D01*
X31360444Y79573721D01*
X30785163Y78998440D01*
X29017397Y78998440D01*
X28442116Y79573721D01*
X28286301Y79399249D01*
X28255851Y78750714D01*
X28078280Y78750714D01*
X28078280Y79471255D01*
X27716403Y80344902D01*
X27047742Y81013563D01*
X26174095Y81375440D01*
X25228465Y81375440D01*
X24354818Y81013563D01*
X23686157Y80344902D01*
X23324280Y79471255D01*
X12678280Y79471255D01*
X12316403Y80344902D01*
X11647742Y81013563D01*
X10774095Y81375440D01*
X9828465Y81375440D01*
X8954818Y81013563D01*
X8286157Y80344902D01*
X7924280Y79471255D01*
X7651953Y79471255D01*
X7560444Y79573721D01*
X6985163Y78998440D01*
X5217397Y78998440D01*
X4642116Y79573721D01*
X4486301Y79399249D01*
X4455851Y78750714D01*
X-3796720Y78750714D01*
X-3796720Y84320439D01*
X2774280Y84320439D01*
X2774280Y83076441D01*
X3250337Y81927137D01*
X4129977Y81047497D01*
X5279281Y80571440D01*
X5653466Y80571440D01*
X5525999Y80457604D01*
X6101280Y79882323D01*
X6676561Y80457604D01*
X6540915Y80578745D01*
X7672583Y81047497D01*
X8552223Y81927137D01*
X9028280Y83076441D01*
X9028280Y84320439D01*
X26974280Y84320439D01*
X26974280Y83076441D01*
X27450337Y81927137D01*
X28329977Y81047497D01*
X29461645Y80578745D01*
X29325999Y80457604D01*
X29901280Y79882323D01*
X30476561Y80457604D01*
X30349094Y80571440D01*
X30723279Y80571440D01*
X31872583Y81047497D01*
X32752223Y81927137D01*
X33228280Y83076441D01*
X33228280Y84320439D01*
X32752223Y85469743D01*
X32622347Y85599619D01*
X52703401Y85599619D01*
X55001280Y83301741D01*
X57299159Y85599619D01*
X56145355Y85953005D01*
X53857205Y85953005D01*
X52703401Y85599619D01*
X32622347Y85599619D01*
X31872583Y86349383D01*
X30723279Y86825440D01*
X29479281Y86825440D01*
X28329977Y86349383D01*
X27450337Y85469743D01*
X26974280Y84320439D01*
X9028280Y84320439D01*
X8552223Y85469743D01*
X7672583Y86349383D01*
X6523279Y86825440D01*
X5279281Y86825440D01*
X4129977Y86349383D01*
X3250337Y85469743D01*
X2774280Y84320439D01*
X-3796720Y84320439D01*
X-3796720Y90719895D01*
X-3625720Y90719895D01*
X-3625720Y89276985D01*
X-3073542Y87943910D01*
X-2053250Y86923618D01*
X-720175Y86371440D01*
X722735Y86371440D01*
X2055810Y86923618D01*
X3076102Y87943910D01*
X3326506Y88548440D01*
X100194280Y88548440D01*
X100194280Y82758440D01*
X100203947Y82709839D01*
X100231477Y82668637D01*
X100264280Y82646719D01*
X100264280Y6828440D01*
X100273947Y6779839D01*
X100301477Y6738637D01*
X105191477Y1848637D01*
X105232679Y1821107D01*
X105281280Y1811440D01*
X121821280Y1811440D01*
X121869881Y1821107D01*
X121911083Y1848637D01*
X127691083Y7628637D01*
X127718613Y7669839D01*
X127728280Y7718440D01*
X127728280Y87728440D01*
X127719075Y87775910D01*
X127691942Y87817375D01*
X124844709Y90719895D01*
X136374280Y90719895D01*
X136374280Y89276985D01*
X136926458Y87943910D01*
X137946750Y86923618D01*
X139279825Y86371440D01*
X140722735Y86371440D01*
X142055810Y86923618D01*
X143076102Y87943910D01*
X143628280Y89276985D01*
X143628280Y90719895D01*
X143076102Y92052970D01*
X142055810Y93073262D01*
X140722735Y93625440D01*
X139279825Y93625440D01*
X137946750Y93073262D01*
X136926458Y92052970D01*
X136374280Y90719895D01*
X124844709Y90719895D01*
X123571942Y92017375D01*
X123529524Y92045920D01*
X123480894Y92055439D01*
X103730894Y91995439D01*
X103684252Y91986412D01*
X103642686Y91959435D01*
X100232686Y88639435D01*
X100203947Y88597041D01*
X100194280Y88548440D01*
X3326506Y88548440D01*
X3628280Y89276985D01*
X3628280Y90719895D01*
X3076102Y92052970D01*
X2055810Y93073262D01*
X722735Y93625440D01*
X-720175Y93625440D01*
X-2053250Y93073262D01*
X-3073542Y92052970D01*
X-3625720Y90719895D01*
X-3796720Y90719895D01*
X-3796720Y92500556D01*
X-2500835Y93796440D01*
X142503396Y93796440D01*
X143799280Y92500555D01*
G36*
X127474280Y87676549D02*
X127474280Y7771046D01*
X121768674Y2065440D01*
X105333886Y2065440D01*
X100518280Y6881046D01*
X100518280Y15362282D01*
X104374280Y15362282D01*
X104374280Y11134598D01*
X105992145Y7228728D01*
X108981568Y4239305D01*
X112887438Y2621440D01*
X117115122Y2621440D01*
X121020992Y4239305D01*
X124010415Y7228728D01*
X125628280Y11134598D01*
X125628280Y15362282D01*
X124010415Y19268152D01*
X121020992Y22257575D01*
X117115122Y23875440D01*
X112887438Y23875440D01*
X108981568Y22257575D01*
X105992145Y19268152D01*
X104374280Y15362282D01*
X100518280Y15362282D01*
X100518280Y37862282D01*
X104374280Y37862282D01*
X104374280Y33634598D01*
X105992145Y29728728D01*
X108981568Y26739305D01*
X112887438Y25121440D01*
X117115122Y25121440D01*
X121020992Y26739305D01*
X124010415Y29728728D01*
X125628280Y33634598D01*
X125628280Y37862282D01*
X124010415Y41768152D01*
X121020992Y44757575D01*
X117115122Y46375440D01*
X112887438Y46375440D01*
X108981568Y44757575D01*
X105992145Y41768152D01*
X104374280Y37862282D01*
X100518280Y37862282D01*
X100518280Y60362282D01*
X104374280Y60362282D01*
X104374280Y56134598D01*
X105992145Y52228728D01*
X108981568Y49239305D01*
X112887438Y47621440D01*
X117115122Y47621440D01*
X121020992Y49239305D01*
X124010415Y52228728D01*
X125628280Y56134598D01*
X125628280Y60362282D01*
X124010415Y64268152D01*
X121020992Y67257575D01*
X117115122Y68875440D01*
X112887438Y68875440D01*
X108981568Y67257575D01*
X105992145Y64268152D01*
X104374280Y60362282D01*
X100518280Y60362282D01*
X100518280Y82748440D01*
X100508613Y82797041D01*
X100481083Y82838243D01*
X100448280Y82861885D01*
X100448280Y82862282D01*
X104374280Y82862282D01*
X104374280Y78634598D01*
X105992145Y74728728D01*
X108981568Y71739305D01*
X112887438Y70121440D01*
X117115122Y70121440D01*
X121020992Y71739305D01*
X124010415Y74728728D01*
X125628280Y78634598D01*
X125628280Y82862282D01*
X124010415Y86768152D01*
X121020992Y89757575D01*
X117115122Y91375440D01*
X112887438Y91375440D01*
X108981568Y89757575D01*
X105992145Y86768152D01*
X104374280Y82862282D01*
X100448280Y82862282D01*
X100448280Y88494837D01*
X103783054Y91741597D01*
X121835603Y91796440D01*
X123432863Y91796440D01*
X127474280Y87676549D01*
X127474280Y87676549D01*
G37*
X127474280Y87676549D02*
X127474280Y7771046D01*
X121768674Y2065440D01*
X105333886Y2065440D01*
X100518280Y6881046D01*
X100518280Y15362282D01*
X104374280Y15362282D01*
X104374280Y11134598D01*
X105992145Y7228728D01*
X108981568Y4239305D01*
X112887438Y2621440D01*
X117115122Y2621440D01*
X121020992Y4239305D01*
X124010415Y7228728D01*
X125628280Y11134598D01*
X125628280Y15362282D01*
X124010415Y19268152D01*
X121020992Y22257575D01*
X117115122Y23875440D01*
X112887438Y23875440D01*
X108981568Y22257575D01*
X105992145Y19268152D01*
X104374280Y15362282D01*
X100518280Y15362282D01*
X100518280Y37862282D01*
X104374280Y37862282D01*
X104374280Y33634598D01*
X105992145Y29728728D01*
X108981568Y26739305D01*
X112887438Y25121440D01*
X117115122Y25121440D01*
X121020992Y26739305D01*
X124010415Y29728728D01*
X125628280Y33634598D01*
X125628280Y37862282D01*
X124010415Y41768152D01*
X121020992Y44757575D01*
X117115122Y46375440D01*
X112887438Y46375440D01*
X108981568Y44757575D01*
X105992145Y41768152D01*
X104374280Y37862282D01*
X100518280Y37862282D01*
X100518280Y60362282D01*
X104374280Y60362282D01*
X104374280Y56134598D01*
X105992145Y52228728D01*
X108981568Y49239305D01*
X112887438Y47621440D01*
X117115122Y47621440D01*
X121020992Y49239305D01*
X124010415Y52228728D01*
X125628280Y56134598D01*
X125628280Y60362282D01*
X124010415Y64268152D01*
X121020992Y67257575D01*
X117115122Y68875440D01*
X112887438Y68875440D01*
X108981568Y67257575D01*
X105992145Y64268152D01*
X104374280Y60362282D01*
X100518280Y60362282D01*
X100518280Y82748440D01*
X100508613Y82797041D01*
X100481083Y82838243D01*
X100448280Y82861885D01*
X100448280Y82862282D01*
X104374280Y82862282D01*
X104374280Y78634598D01*
X105992145Y74728728D01*
X108981568Y71739305D01*
X112887438Y70121440D01*
X117115122Y70121440D01*
X121020992Y71739305D01*
X124010415Y74728728D01*
X125628280Y78634598D01*
X125628280Y82862282D01*
X124010415Y86768152D01*
X121020992Y89757575D01*
X117115122Y91375440D01*
X112887438Y91375440D01*
X108981568Y89757575D01*
X105992145Y86768152D01*
X104374280Y82862282D01*
X100448280Y82862282D01*
X100448280Y88494837D01*
X103783054Y91741597D01*
X121835603Y91796440D01*
X123432863Y91796440D01*
X127474280Y87676549D01*
G04 #@! TD*
M02*
